# T6G (Grand Teton) — schematic netlist excerpt (pin names and nets, part order shuffled) for the footprints in the layout excerpt that follows; sources: Cadence DE-HDL packaged netlist, KiCad conversion of 04192023_DAF0TMB3IC0_F0TG_MB_C_brd_V02_OCP.brd

PR159  Q_RES  5.23K 1% CHIP  pkg 0402LF  page 210 : A = PVDDCR_SOC_P1_EN//ADDR_CFG ; B = GND
TP4  TP  NA  pkg TP  page 27 : TP = VSENSE_PVDD18_S5_P0_DN
R2894  Q_RES  0 5% EMPTY  pkg 0402LF  page 248 : A = SMB_1_BMC_GPU_R_SDA ; B = SMB_1_BMC_GPU_BUF_R_SDA

(kicad_pcb
	(version 20260206)
	(generator "pcbnew")
	(generator_version "10.0")
	(general
		(thickness 1.6)
		(legacy_teardrops no)
	)
	(paper "A4")
	(title_block
		(title "04192023_DAF0TMB3IC0_F0TG_MB_C_brd_V02_OCP.brd")
		(comment 1 "Grand Teton / footprints 2401-2403 of 8354")
	)
	(layers
		(0 "F.Cu" signal "TOP")
		(4 "In1.Cu" signal "GND")
		(6 "In2.Cu" signal "IN1")
		(8 "In3.Cu" signal "GND1")
		(10 "In4.Cu" signal "IN2")
		(12 "In5.Cu" signal "GND2")
		(14 "In6.Cu" signal "IN3")
		(16 "In7.Cu" signal "GND3")
		(18 "In8.Cu" signal "VCC")
		(20 "In9.Cu" signal "VCC1")
		(22 "In10.Cu" signal "GND4")
		(24 "In11.Cu" signal "IN4")
		(26 "In12.Cu" signal "GND5")
		(28 "In13.Cu" signal "IN5")
		(30 "In14.Cu" signal "GND6")
		(32 "In15.Cu" signal "IN6")
		(34 "In16.Cu" signal "GND7")
		(2 "B.Cu" signal "BOTTOM")
		(9 "F.Adhes" user "F.Adhesive")
		(11 "B.Adhes" user "B.Adhesive")
		(13 "F.Paste" user "Package Geometry/Pastemask Top")
		(15 "B.Paste" user "Package Geometry/Pastemask Bottom")
		(5 "F.SilkS" user "Ref Des/Silkscreen Top")
		(7 "B.SilkS" user "Ref Des/Silkscreen Bottom")
		(1 "F.Mask" user "Board Geometry/Soldermask Top")
		(3 "B.Mask" user "Board Geometry/Soldermask Bottom")
		(17 "Dwgs.User" user "User.Drawings")
		(19 "Cmts.User" user "User.Comments")
		(21 "Eco1.User" user "User.Eco1")
		(23 "Eco2.User" user "User.Eco2")
		(25 "Edge.Cuts" user "Board Geometry/Outline")
		(27 "Margin" user)
		(31 "F.CrtYd" user "Package Geometry/Place Bound Top")
		(29 "B.CrtYd" user "Package Geometry/Place Bound Bottom")
		(35 "F.Fab" user "Ref Des/Assembly Top")
		(33 "B.Fab" user "Ref Des/Assembly Bottom")
	)
	(footprint ""
		(layer "F.Cu")
		(at 33.63468 -432.564794 90)
		(property "Reference" "R2894"
			(at 0 0 90)
			(layer "F.SilkS")
			(hide yes)
			(effects
				(font
					(size 1.27 1.27)
				)
			)
		)
		(property "Value" ""
			(at 0 0 90)
			(layer "F.Fab")
			(effects
				(font
					(size 1.27 1.27)
				)
			)
		)
		(duplicate_pad_numbers_are_jumpers no)
		(fp_line
			(start 0.7874 -0.4064)
			(end 0.7874 0.4064)
			(stroke
				(width 0.1524)
				(type default)
			)
			(layer "F.SilkS")
		)
		(fp_line
			(start -0.7874 -0.4064)
			(end 0.7874 -0.4064)
			(stroke
				(width 0.1524)
				(type default)
			)
			(layer "F.SilkS")
		)
		(fp_line
			(start 0.7874 0.4064)
			(end -0.7874 0.4064)
			(stroke
				(width 0.1524)
				(type default)
			)
			(layer "F.SilkS")
		)
		(fp_line
			(start -0.7874 0.4064)
			(end -0.7874 -0.4064)
			(stroke
				(width 0.1524)
				(type default)
			)
			(layer "F.SilkS")
		)
		(fp_line
			(start -0.12065 -0.305054)
			(end -0.12065 -0.2794)
			(stroke
				(width 0.1)
				(type default)
			)
			(layer "F.Fab")
		)
		(fp_line
			(start -0.67945 -0.305054)
			(end -0.12065 -0.305054)
			(stroke
				(width 0.1)
				(type default)
			)
			(layer "F.Fab")
		)
		(fp_line
			(start 0.67945 -0.3048)
			(end 0.67945 0.3048)
			(stroke
				(width 0.1)
				(type default)
			)
			(layer "F.Fab")
		)
		(fp_line
			(start 0.12065 -0.3048)
			(end 0.67945 -0.3048)
			(stroke
				(width 0.1)
				(type default)
			)
			(layer "F.Fab")
		)
		(fp_line
			(start 0.12065 -0.2794)
			(end 0.12065 -0.3048)
			(stroke
				(width 0.1)
				(type default)
			)
			(layer "F.Fab")
		)
		(fp_line
			(start -0.12065 -0.2794)
			(end 0.12065 -0.2794)
			(stroke
				(width 0.1)
				(type default)
			)
			(layer "F.Fab")
		)
		(fp_line
			(start 0.120396 0.2794)
			(end -0.12065 0.2794)
			(stroke
				(width 0.1)
				(type default)
			)
			(layer "F.Fab")
		)
		(fp_line
			(start -0.12065 0.2794)
			(end -0.12065 0.3048)
			(stroke
				(width 0.1)
				(type default)
			)
			(layer "F.Fab")
		)
		(fp_line
			(start 0.67945 0.3048)
			(end 0.120396 0.3048)
			(stroke
				(width 0.1)
				(type default)
			)
			(layer "F.Fab")
		)
		(fp_line
			(start 0.120396 0.3048)
			(end 0.120396 0.2794)
			(stroke
				(width 0.1)
				(type default)
			)
			(layer "F.Fab")
		)
		(fp_line
			(start -0.12065 0.3048)
			(end -0.67945 0.3048)
			(stroke
				(width 0.1)
				(type default)
			)
			(layer "F.Fab")
		)
		(fp_line
			(start -0.67945 0.3048)
			(end -0.67945 -0.305054)
			(stroke
				(width 0.1)
				(type default)
			)
			(layer "F.Fab")
		)
		(pad "1" smd circle
			(at -0.40005 0 90)
			(size 0 0)
			(layers "F.Cu" "F.Mask" "F.Paste")
			(net "SMB_1_BMC_GPU_R_SDA")
		)
		(pad "2" smd circle
			(at 0.40005 0 90)
			(size 0 0)
			(layers "F.Cu" "F.Mask" "F.Paste")
			(net "SMB_1_BMC_GPU_BUF_R_SDA")
		)
	)
	(footprint ""
		(layer "F.Cu")
		(at 303.69383 -152.875742 180)
		(property "Reference" "TP4"
			(at 2.89814 -0.282194 0)
			(unlocked yes)
			(layer "F.SilkS")
			(effects
				(font
					(size 0.7874 0.5842)
					(thickness 0.1524)
				)
				(justify left)
			)
		)
		(property "Value" ""
			(at 0 0 180)
			(layer "F.Fab")
			(effects
				(font
					(size 1.27 1.27)
				)
			)
		)
		(duplicate_pad_numbers_are_jumpers no)
		(pad "1" smd circle
			(at 0 0 180)
			(size 0.762 0.762)
			(layers "F.Cu" "F.Mask" "F.Paste")
			(net "VSENSE_PVDD18_S5_P0_DN")
		)
	)
	(footprint ""
		(layer "F.Cu")
		(at 98.795078 -145.06321 180)
		(property "Reference" "PR159"
			(at 0 0 180)
			(layer "F.SilkS")
			(hide yes)
			(effects
				(font
					(size 1.27 1.27)
				)
			)
		)
		(property "Value" ""
			(at 0 0 180)
			(layer "F.Fab")
			(effects
				(font
					(size 1.27 1.27)
				)
			)
		)
		(duplicate_pad_numbers_are_jumpers no)
		(fp_line
			(start 0.7874 0.4064)
			(end -0.7874 0.4064)
			(stroke
				(width 0.1524)
				(type default)
			)
			(layer "F.SilkS")
		)
		(fp_line
			(start 0.7874 -0.4064)
			(end 0.7874 0.4064)
			(stroke
				(width 0.1524)
				(type default)
			)
			(layer "F.SilkS")
		)
		(fp_line
			(start -0.7874 0.4064)
			(end -0.7874 -0.4064)
			(stroke
				(width 0.1524)
				(type default)
			)
			(layer "F.SilkS")
		)
		(fp_line
			(start -0.7874 -0.4064)
			(end 0.7874 -0.4064)
			(stroke
				(width 0.1524)
				(type default)
			)
			(layer "F.SilkS")
		)
		(fp_line
			(start 0.67945 0.3048)
			(end 0.120396 0.3048)
			(stroke
				(width 0.1)
				(type default)
			)
			(layer "F.Fab")
		)
		(fp_line
			(start 0.67945 -0.3048)
			(end 0.67945 0.3048)
			(stroke
				(width 0.1)
				(type default)
			)
			(layer "F.Fab")
		)
		(fp_line
			(start 0.12065 -0.2794)
			(end 0.12065 -0.3048)
			(stroke
				(width 0.1)
				(type default)
			)
			(layer "F.Fab")
		)
		(fp_line
			(start 0.12065 -0.3048)
			(end 0.67945 -0.3048)
			(stroke
				(width 0.1)
				(type default)
			)
			(layer "F.Fab")
		)
		(fp_line
			(start 0.120396 0.3048)
			(end 0.120396 0.2794)
			(stroke
				(width 0.1)
				(type default)
			)
			(layer "F.Fab")
		)
		(fp_line
			(start 0.120396 0.2794)
			(end -0.12065 0.2794)
			(stroke
				(width 0.1)
				(type default)
			)
			(layer "F.Fab")
		)
		(fp_line
			(start -0.12065 0.3048)
			(end -0.67945 0.3048)
			(stroke
				(width 0.1)
				(type default)
			)
			(layer "F.Fab")
		)
		(fp_line
			(start -0.12065 0.2794)
			(end -0.12065 0.3048)
			(stroke
				(width 0.1)
				(type default)
			)
			(layer "F.Fab")
		)
		(fp_line
			(start -0.12065 -0.2794)
			(end 0.12065 -0.2794)
			(stroke
				(width 0.1)
				(type default)
			)
			(layer "F.Fab")
		)
		(fp_line
			(start -0.12065 -0.305054)
			(end -0.12065 -0.2794)
			(stroke
				(width 0.1)
				(type default)
			)
			(layer "F.Fab")
		)
		(fp_line
			(start -0.67945 0.3048)
			(end -0.67945 -0.305054)
			(stroke
				(width 0.1)
				(type default)
			)
			(layer "F.Fab")
		)
		(fp_line
			(start -0.67945 -0.305054)
			(end -0.12065 -0.305054)
			(stroke
				(width 0.1)
				(type default)
			)
			(layer "F.Fab")
		)
		(pad "1" smd circle
			(at -0.40005 0 180)
			(size 0 0)
			(layers "F.Cu" "F.Mask" "F.Paste")
			(net "PVDDCR_SOC_P1_EN//ADDR_CFG")
		)
		(pad "2" smd circle
			(at 0.40005 0 180)
			(size 0 0)
			(layers "F.Cu" "F.Mask" "F.Paste")
			(net "GND")
		)
	)
)
